FILE_TYPE = MULTI_PHYS_TABLE;
PART 'W25Q256'
{=======================================================================================================================================================================}
:PACK_TYPE | MATERIAL | PART_NUMBER     = EnvComp | PART_NUMBER  | JEDEC_TYPE      | DESCRIPTION                        | CLASS | COMPONENT_TYPE | HEIGHT     | LPID   | SPEED_URL | Status |RPL| AML | Bus_Unit | Days ;
{=======================================================================================================================================================================}
'SMT'      | 'IC'     | 'H25002-001'(!) = 'YES;YES;YES;UNK;ok;VLD' | 'H25002-001' | 'SOI16_30_50IB' | 'IC,FLASH,SPI NOR 256MBIT,SOIC,16' | 'IC'  | 'SOIC'  | '0.104 IN' | '1353' | 'http://speed.intel.com:8081/speed/module/pdm/item/pdm_item_detail_direct.asp?item_cde=H25002-001&item_rev=01&url_param=unused' | 'Design' | 'NO' | '1' | 'SMO_IC' | '???' 
'SMT'      | 'EMPTY'  | 'H25002-001'(!) = 'YES;YES;YES;UNK;ok;VLD' | 'H25002-001' | 'SOI16_30_50IB' | 'IC,FLASH,SPI NOR 256MBIT,SOIC,16' | 'IO'  | 'SOIC'  | '0.104 IN' | '1353' | 'http://speed.intel.com:8081/speed/module/pdm/item/pdm_item_detail_direct.asp?item_cde=H25002-001&item_rev=01&url_param=unused' | 'Design' | 'NO' | '1' | 'SMO_IC' | '???' 
{LINES BELOW WILL BE REMOVED AFTER 12/5/14}
'XSOI'     | 'IC'     | 'H25002-001'(!) = 'YES;YES;YES;UNK;ok;VLD' | 'H25002-001' | 'XSOI16_30_50IA'| 'IC,FLASH,SPI NOR 256MBIT,SOIC,16' | 'IC'  | 'SOIC'  | '0.104 IN' | ''     | 'http://speed.intel.com:8081/speed/module/pdm/item/pdm_item_detail_direct.asp?item_cde=H25002-001&item_rev=01&url_param=unused' | 'Design' | 'NO' | '1' | 'SMO_IC' | '???' 
'XSOI'     | 'EMPTY'  | 'H25002-001'(!) = 'YES;YES;YES;UNK;ok;VLD' | 'H25002-001' | 'XSOI16_30_50IA'| 'IC,FLASH,SPI NOR 256MBIT,SOIC,16' | 'IO'  | 'SOIC'  | '0.104 IN' | ''     | 'http://speed.intel.com:8081/speed/module/pdm/item/pdm_item_detail_direct.asp?item_cde=H25002-001&item_rev=01&url_param=unused' | 'Design' | 'NO' | '1' | 'SMO_IC' | '???' 
END_PART
END.
